(kicad_pcb
	(version 20211014)
	(generator pcbnew)
	(general
    (thickness 1.6)
  )
	(paper "A4")
	(title_block
    (title "SA800U (Snapdragon 845) Baseboard")
    (date "2023-10-19")
    (rev "1.0.3")
    (company "Antmicro Ltd.")
    (comment 1 "www.antmicro.com")
		(comment 9 "footprints 1-7 of 589")
	)
	(layers
    (0 "F.Cu" signal)
    (1 "In1.Cu" power)
    (2 "In2.Cu" signal)
    (3 "In3.Cu" signal)
    (4 "In4.Cu" power)
    (31 "B.Cu" signal)
    (32 "B.Adhes" user "B.Adhesive")
    (33 "F.Adhes" user "F.Adhesive")
    (34 "B.Paste" user)
    (35 "F.Paste" user)
    (36 "B.SilkS" user "B.Silkscreen")
    (37 "F.SilkS" user "F.Silkscreen")
    (38 "B.Mask" user)
    (39 "F.Mask" user)
    (40 "Dwgs.User" user "User.Drawings")
    (41 "Cmts.User" user "User.Comments")
    (42 "Eco1.User" user "User.Eco1")
    (43 "Eco2.User" user "User.Eco2")
    (44 "Edge.Cuts" user)
    (45 "Margin" user)
    (46 "B.CrtYd" user "B.Courtyard")
    (47 "F.CrtYd" user "F.Courtyard")
    (48 "B.Fab" user)
    (49 "F.Fab" user)
  )
	(footprint "sa800u-baseboard-hw-footprints:C_0402_1005Metric" (layer "F.Cu")
    (tedit 616D63CF)
    (at 106 92.4 -90)
    (descr "Capacitor SMD 0402")
    (tags "capacitor SMD 0402")
    (property "Author" "Antmicro")
    (property "Dielectric" "X5R")
    (property "License" "Apache-2.0")
    (property "MPN" "GRM155R61H104KE14D")
    (property "Manufacturer" "Murata")
    (property "Sheetfile" "ethernet-controller.kicad_sch")
    (property "Sheetname" "Ethernet Controller")
    (property "Val" "100n")
    (property "Voltage" "50V")
    (attr smd)
    (fp_text reference "C7" (at 2.32 -0.33 -90) (layer "F.SilkS")
      (effects (font (size 0.7 0.7) (thickness 0.15)) (justify left bottom))
    )
    (fp_text value "C_100n_0402" (at 0 1.4 -90) (layer "F.Fab")
      (effects (font (size 0.7 0.7) (thickness 0.15)) (justify left bottom))
    )
    (fp_text user "License: Apache-2.0" (at -0.932 5.17 -90) (layer "F.Fab") hide
      (effects (font (size 0.7 0.7) (thickness 0.15)) (justify left bottom))
    )
    (fp_text user "Author: Antmicro" (at -0.932 4.17 -90) (layer "F.Fab") hide
      (effects (font (size 0.7 0.7) (thickness 0.15)) (justify left bottom))
    )
    (fp_text user "${REFERENCE}" (at -0.932 3.168 -90) (layer "F.Fab") hide
      (effects (font (size 0.7 0.7) (thickness 0.15)) (justify left bottom))
    )
    (fp_rect (start -0.94 -0.47) (end 0.94 0.47) (layer "F.CrtYd") (width 0.05) (fill none))
    (fp_rect (start -0.499 -0.249) (end 0.499 0.249) (layer "F.Fab") (width 0.15) (fill none))
    (pad "1" smd roundrect (at -0.484 0 270) (size 0.59 0.64) (layers "F.Cu" "F.Paste" "F.Mask") (roundrect_rratio 0.25)
      (net 8 "PCIE1_RX_P") (pintype "passive"))
    (pad "2" smd roundrect (at 0.484 0 270) (size 0.59 0.64) (layers "F.Cu" "F.Paste" "F.Mask") (roundrect_rratio 0.25)
      (net 179 "/Ethernet Controller/PCIE1_RX_C_P") (pintype "passive"))
  )
	(footprint "sa800u-baseboard-hw-footprints:C_0402_1005Metric" (layer "F.Cu")
    (tedit 616D63CF)
    (at 105 92.4 -90)
    (descr "Capacitor SMD 0402")
    (tags "capacitor SMD 0402")
    (property "Author" "Antmicro")
    (property "Dielectric" "X5R")
    (property "License" "Apache-2.0")
    (property "MPN" "GRM155R61H104KE14D")
    (property "Manufacturer" "Murata")
    (property "Sheetfile" "ethernet-controller.kicad_sch")
    (property "Sheetname" "Ethernet Controller")
    (property "Val" "100n")
    (property "Voltage" "50V")
    (attr smd)
    (fp_text reference "C6" (at 2.32 -0.33 -90) (layer "F.SilkS")
      (effects (font (size 0.7 0.7) (thickness 0.15)) (justify left bottom))
    )
    (fp_text value "C_100n_0402" (at 0 1.4 -90) (layer "F.Fab")
      (effects (font (size 0.7 0.7) (thickness 0.15)) (justify left bottom))
    )
    (fp_text user "${REFERENCE}" (at -0.932 3.168 -90) (layer "F.Fab") hide
      (effects (font (size 0.7 0.7) (thickness 0.15)) (justify left bottom))
    )
    (fp_text user "License: Apache-2.0" (at -0.932 5.17 -90) (layer "F.Fab") hide
      (effects (font (size 0.7 0.7) (thickness 0.15)) (justify left bottom))
    )
    (fp_text user "Author: Antmicro" (at -0.932 4.17 -90) (layer "F.Fab") hide
      (effects (font (size 0.7 0.7) (thickness 0.15)) (justify left bottom))
    )
    (fp_rect (start -0.94 -0.47) (end 0.94 0.47) (layer "F.CrtYd") (width 0.05) (fill none))
    (fp_rect (start -0.499 -0.249) (end 0.499 0.249) (layer "F.Fab") (width 0.15) (fill none))
    (pad "1" smd roundrect (at -0.484 0 270) (size 0.59 0.64) (layers "F.Cu" "F.Paste" "F.Mask") (roundrect_rratio 0.25)
      (net 9 "PCIE1_RX_N") (pintype "passive"))
    (pad "2" smd roundrect (at 0.484 0 270) (size 0.59 0.64) (layers "F.Cu" "F.Paste" "F.Mask") (roundrect_rratio 0.25)
      (net 180 "/Ethernet Controller/PCIE1_RX_C_N") (pintype "passive"))
  )
	(footprint "sa800u-baseboard-hw-footprints:C_Elec_10x10.5mm" (layer "F.Cu")
    (tedit 5ED8C968)
    (at 62 124.7 180)
    (descr "SMD capacitor, aluminum electrolytic, 10x10.5mm")
    (tags "capacitor electrolytic")
    (property "Author" "Antmicro")
    (property "Dielectric" "")
    (property "License" "Apache-2.0")
    (property "MPN" "EEEHA2A470UP")
    (property "Manufacturer" "Panasonic")
    (property "Sheetfile" "poe.kicad_sch")
    (property "Sheetname" "PoE")
    (property "Val" "47u/100V")
    (property "Voltage" "")
    (attr smd)
    (fp_text reference "C146" (at 5.75 1.77 90) (layer "F.SilkS")
      (effects (font (size 0.7 0.7) (thickness 0.15)) (justify left bottom))
    )
    (fp_text value "C_47u_ELEC_100V" (at 0 6.299 180) (layer "F.Fab")
      (effects (font (size 0.7 0.7) (thickness 0.15)) (justify left bottom))
    )
    (fp_text user "Author: Antmicro" (at -6.85 9.499 180) (layer "F.Fab") hide
      (effects (font (size 0.7 0.7) (thickness 0.15)) (justify left bottom))
    )
    (fp_text user "License: Apache-2.0" (at -6.85 10.699 180) (layer "F.Fab") hide
      (effects (font (size 0.7 0.7) (thickness 0.15)) (justify left bottom))
    )
    (fp_text user "${REFERENCE}" (at -6.85 8.3 180) (layer "F.Fab") hide
      (effects (font (size 0.7 0.7) (thickness 0.15)) (justify left bottom))
    )
    (fp_line (start -5.361 4.295) (end -4.296 5.36) (layer "F.SilkS") (width 0.15))
    (fp_line (start -6.85 -2.76) (end -5.6 -2.76) (layer "F.SilkS") (width 0.15))
    (fp_line (start -5.361 -4.296) (end -4.296 -5.361) (layer "F.SilkS") (width 0.15))
    (fp_line (start -5.361 -4.296) (end -5.361 -1.51) (layer "F.SilkS") (width 0.15))
    (fp_line (start -4.296 5.36) (end 5.36 5.36) (layer "F.SilkS") (width 0.15))
    (fp_line (start -5.361 4.295) (end -5.361 1.509) (layer "F.SilkS") (width 0.15))
    (fp_line (start -4.296 -5.361) (end 5.36 -5.361) (layer "F.SilkS") (width 0.15))
    (fp_line (start 5.36 -5.361) (end 5.36 -1.51) (layer "F.SilkS") (width 0.15))
    (fp_line (start -6.225 -3.385) (end -6.225 -2.135) (layer "F.SilkS") (width 0.15))
    (fp_line (start 5.36 5.36) (end 5.36 1.509) (layer "F.SilkS") (width 0.15))
    (fp_line (start 6.65 -1.5) (end 6.65 1.49) (layer "F.CrtYd") (width 0.05))
    (fp_line (start -4.35 5.49) (end 5.49 5.49) (layer "F.CrtYd") (width 0.05))
    (fp_line (start -6.66 -1.5) (end -6.66 1.49) (layer "F.CrtYd") (width 0.05))
    (fp_line (start -5.5 -4.35) (end -4.35 -5.5) (layer "F.CrtYd") (width 0.05))
    (fp_line (start 5.49 -1.5) (end 6.65 -1.5) (layer "F.CrtYd") (width 0.05))
    (fp_line (start -5.5 1.49) (end -5.5 4.34) (layer "F.CrtYd") (width 0.05))
    (fp_line (start -5.5 -1.5) (end -6.66 -1.5) (layer "F.CrtYd") (width 0.05))
    (fp_line (start 5.49 1.49) (end 5.49 5.49) (layer "F.CrtYd") (width 0.05))
    (fp_line (start -5.5 4.34) (end -4.35 5.49) (layer "F.CrtYd") (width 0.05))
    (fp_line (start -6.66 1.49) (end -5.5 1.49) (layer "F.CrtYd") (width 0.05))
    (fp_line (start 5.49 -5.5) (end 5.49 -1.5) (layer "F.CrtYd") (width 0.05))
    (fp_line (start -4.35 -5.5) (end 5.49 -5.5) (layer "F.CrtYd") (width 0.05))
    (fp_line (start 6.65 1.49) (end 5.49 1.49) (layer "F.CrtYd") (width 0.05))
    (fp_line (start -5.5 -4.35) (end -5.5 -1.5) (layer "F.CrtYd") (width 0.05))
    (fp_line (start -5.25 -4.25) (end -4.25 -5.25) (layer "F.Fab") (width 0.15))
    (fp_line (start -4.25 -5.25) (end 5.249 -5.25) (layer "F.Fab") (width 0.15))
    (fp_line (start -5.25 -4.25) (end -5.25 4.249) (layer "F.Fab") (width 0.15))
    (fp_line (start -4.559 -1.7) (end -3.559 -1.7) (layer "F.Fab") (width 0.15))
    (fp_line (start -5.25 4.249) (end -4.25 5.249) (layer "F.Fab") (width 0.15))
    (fp_line (start 5.249 -5.25) (end 5.249 5.249) (layer "F.Fab") (width 0.15))
    (fp_line (start -4.059 -2.201) (end -4.059 -1.2) (layer "F.Fab") (width 0.15))
    (fp_line (start -4.25 5.249) (end 5.249 5.249) (layer "F.Fab") (width 0.15))
    (fp_circle (center 0 0) (end 4.999 0) (layer "F.Fab") (width 0.15) (fill none))
    (pad "1" smd roundrect (at -4.201 0 180) (size 4.4 2.5) (layers "F.Cu" "F.Paste" "F.Mask") (roundrect_rratio 0.1)
      (net 73 "/PoE/VDD_POE") (pintype "passive"))
    (pad "2" smd roundrect (at 4.2 0 180) (size 4.4 2.5) (layers "F.Cu" "F.Paste" "F.Mask") (roundrect_rratio 0.1)
      (net 7 "GNDD") (pintype "passive"))
  )
	(footprint "sa800u-baseboard-hw-footprints:R_0402_1005Metric" (layer "F.Cu")
    (tedit 5FD9C158)
    (at 140 142.5)
    (descr "Resistor SMD 0402")
    (tags "resistor SMD 0402")
    (property "Author" "Antmicro")
    (property "License" "Apache-2.0")
    (property "MPN" "CR0402-FX-2201GLF")
    (property "Manufacturer" "Bourns")
    (property "Sheetfile" "hdmi-converter.kicad_sch")
    (property "Sheetname" "HDMI converter")
    (property "Tolerance" "1%")
    (property "Val" "2k2")
    (attr smd)
    (fp_text reference "R28" (at -3.05 0.35) (layer "F.SilkS")
      (effects (font (size 0.7 0.7) (thickness 0.15)) (justify left bottom))
    )
    (fp_text value "R_2k2_0402" (at 0 1.4) (layer "F.Fab")
      (effects (font (size 0.7 0.7) (thickness 0.15)) (justify left bottom))
    )
    (fp_text user "${REFERENCE}" (at -0.95 3.168) (layer "F.Fab") hide
      (effects (font (size 0.7 0.7) (thickness 0.15)) (justify left bottom))
    )
    (fp_text user "Author: Antmicro" (at -0.95 4.169) (layer "F.Fab") hide
      (effects (font (size 0.7 0.7) (thickness 0.15)) (justify left bottom))
    )
    (fp_text user "License: Apache-2.0" (at -0.95 5.169) (layer "F.Fab") hide
      (effects (font (size 0.7 0.7) (thickness 0.15)) (justify left bottom))
    )
    (fp_rect (start -0.93 -0.47) (end 0.93 0.47) (layer "F.CrtYd") (width 0.05) (fill none))
    (fp_rect (start -0.5 -0.25) (end 0.5 0.25) (layer "F.Fab") (width 0.15) (fill none))
    (pad "1" smd roundrect (at -0.485 0) (size 0.59 0.64) (layers "F.Cu" "F.Paste" "F.Mask") (roundrect_rratio 0.25)
      (net 133 "5V_SYS") (pintype "passive"))
    (pad "2" smd roundrect (at 0.485 0) (size 0.59 0.64) (layers "F.Cu" "F.Paste" "F.Mask") (roundrect_rratio 0.25)
      (net 232 "/HDMI converter/HDMI_SCL") (pintype "passive"))
  )
	(footprint "sa800u-baseboard-hw-footprints:R_0402_1005Metric" (layer "F.Cu")
    (tedit 5FD9C158)
    (at 140 141.5)
    (descr "Resistor SMD 0402")
    (tags "resistor SMD 0402")
    (property "Author" "Antmicro")
    (property "License" "Apache-2.0")
    (property "MPN" "CR0402-FX-2201GLF")
    (property "Manufacturer" "Bourns")
    (property "Sheetfile" "hdmi-converter.kicad_sch")
    (property "Sheetname" "HDMI converter")
    (property "Tolerance" "1%")
    (property "Val" "2k2")
    (attr smd)
    (fp_text reference "R32" (at -3.05 0.35) (layer "F.SilkS")
      (effects (font (size 0.7 0.7) (thickness 0.15)) (justify left bottom))
    )
    (fp_text value "R_2k2_0402" (at 0 1.4) (layer "F.Fab")
      (effects (font (size 0.7 0.7) (thickness 0.15)) (justify left bottom))
    )
    (fp_text user "${REFERENCE}" (at -0.95 3.168) (layer "F.Fab") hide
      (effects (font (size 0.7 0.7) (thickness 0.15)) (justify left bottom))
    )
    (fp_text user "License: Apache-2.0" (at -0.95 5.169) (layer "F.Fab") hide
      (effects (font (size 0.7 0.7) (thickness 0.15)) (justify left bottom))
    )
    (fp_text user "Author: Antmicro" (at -0.95 4.169) (layer "F.Fab") hide
      (effects (font (size 0.7 0.7) (thickness 0.15)) (justify left bottom))
    )
    (fp_rect (start -0.93 -0.47) (end 0.93 0.47) (layer "F.CrtYd") (width 0.05) (fill none))
    (fp_rect (start -0.5 -0.25) (end 0.5 0.25) (layer "F.Fab") (width 0.15) (fill none))
    (pad "1" smd roundrect (at -0.485 0) (size 0.59 0.64) (layers "F.Cu" "F.Paste" "F.Mask") (roundrect_rratio 0.25)
      (net 133 "5V_SYS") (pintype "passive"))
    (pad "2" smd roundrect (at 0.485 0) (size 0.59 0.64) (layers "F.Cu" "F.Paste" "F.Mask") (roundrect_rratio 0.25)
      (net 235 "/HDMI converter/HDMI_SDA") (pintype "passive"))
  )
	(footprint "sa800u-baseboard-hw-footprints:SW_SPST_4.2x2.8" (layer "F.Cu")
    (tedit 5DF0C83F)
    (at 152 93.5)
    (descr "KMR211G")
    (tags "SPST Button Switch")
    (property "Author" "Antmicro")
    (property "License" "Apache-2.0")
    (property "MPN" "KMR211NGLFS")
    (property "Manufacturer" "C&K")
    (property "Sheetfile" "som.kicad_sch")
    (property "Sheetname" "SoM")
    (attr smd)
    (fp_text reference "S1" (at -3 -2.25) (layer "F.SilkS")
      (effects (font (size 0.7 0.7) (thickness 0.15)) (justify left bottom))
    )
    (fp_text value "SW_SPST_KMR211NGLFS" (at -3 3) (layer "F.Fab")
      (effects (font (size 0.7 0.7) (thickness 0.15)) (justify left bottom))
    )
    (fp_text user "${REFERENCE}" (at -3 4.25) (layer "F.Fab") hide
      (effects (font (size 0.7 0.7) (thickness 0.15)) (justify left bottom))
    )
    (fp_text user "Author: Antmicro" (at -3 5.5) (layer "F.Fab") hide
      (effects (font (size 0.7 0.7) (thickness 0.15)) (justify left bottom))
    )
    (fp_text user "License: Apache-2.0" (at -3 6.75) (layer "F.Fab") hide
      (effects (font (size 0.7 0.7) (thickness 0.15)) (justify left bottom))
    )
    (fp_line (start -2.101 -1.601) (end 2.1 -1.601) (layer "F.SilkS") (width 0.15))
    (fp_line (start 2.1 1.6) (end 2.1 1.499) (layer "F.SilkS") (width 0.15))
    (fp_line (start -2.101 -1.601) (end -2.101 -1.48) (layer "F.SilkS") (width 0.15))
    (fp_line (start 2.1 -1.601) (end 2.1 -1.48) (layer "F.SilkS") (width 0.15))
    (fp_line (start -2.101 1.58) (end -2.101 1.459) (layer "F.SilkS") (width 0.15))
    (fp_line (start -2.101 1.6) (end 2.1 1.6) (layer "F.SilkS") (width 0.15))
    (fp_rect (start -2.751 -1.75) (end 2.748 1.749) (layer "F.CrtYd") (width 0.05) (fill none))
    (fp_line (start -2.101 1.6) (end 2.1 1.6) (layer "F.Fab") (width 0.15))
    (fp_line (start 0.248 0.8) (end -0.25 0.8) (layer "F.Fab") (width 0.15))
    (fp_line (start -2.101 -1.601) (end -2.101 1.6) (layer "F.Fab") (width 0.15))
    (fp_line (start 2.1 1.6) (end 2.1 -1.601) (layer "F.Fab") (width 0.15))
    (fp_line (start 2.1 -1.601) (end -2.101 -1.601) (layer "F.Fab") (width 0.15))
    (fp_line (start -0.25 -0.802) (end 0.248 -0.802) (layer "F.Fab") (width 0.15))
    (fp_arc (start -0.25 0.8) (mid -1.051001 -0.001) (end -0.25 -0.802) (layer "F.Fab") (width 0.15))
    (fp_arc (start 0.248 -0.802) (mid 1.050001 -0.001) (end 0.248 0.8) (layer "F.Fab") (width 0.15))
    (pad "1" smd rect (at 2.048 -0.802) (size 0.9 1) (layers "F.Cu" "F.Paste" "F.Mask")
      (net 1 "GND") (pintype "passive"))
    (pad "2" smd rect (at 2.048 0.8) (size 0.9 1) (layers "F.Cu" "F.Paste" "F.Mask")
      (net 344 "/SoM/HOME_KEY_R") (pintype "passive"))
    (pad "3" smd rect (at -2.05 -0.802) (size 0.9 1) (layers "F.Cu" "F.Paste" "F.Mask")
      (net 1 "GND") (pintype "passive"))
    (pad "4" smd rect (at -2.05 0.8) (size 0.9 1) (layers "F.Cu" "F.Paste" "F.Mask")
      (net 344 "/SoM/HOME_KEY_R") (pintype "passive"))
  )
	(footprint "sa800u-baseboard-hw-footprints:SW_SPST_4.2x2.8" (layer "F.Cu")
    (tedit 5DF0C83F)
    (at 152 99.5)
    (descr "KMR211G")
    (tags "SPST Button Switch")
    (property "Author" "Antmicro")
    (property "License" "Apache-2.0")
    (property "MPN" "KMR211NGLFS")
    (property "Manufacturer" "C&K")
    (property "Sheetfile" "som.kicad_sch")
    (property "Sheetname" "SoM")
    (attr smd)
    (fp_text reference "S2" (at -2.44 -1.87) (layer "F.SilkS")
      (effects (font (size 0.7 0.7) (thickness 0.15)) (justify left bottom))
    )
    (fp_text value "SW_SPST_KMR211NGLFS" (at -3 3) (layer "F.Fab")
      (effects (font (size 0.7 0.7) (thickness 0.15)) (justify left bottom))
    )
    (fp_text user "${REFERENCE}" (at -3 4.25) (layer "F.Fab") hide
      (effects (font (size 0.7 0.7) (thickness 0.15)) (justify left bottom))
    )
    (fp_text user "Author: Antmicro" (at -3 5.5) (layer "F.Fab") hide
      (effects (font (size 0.7 0.7) (thickness 0.15)) (justify left bottom))
    )
    (fp_text user "License: Apache-2.0" (at -3 6.75) (layer "F.Fab") hide
      (effects (font (size 0.7 0.7) (thickness 0.15)) (justify left bottom))
    )
    (fp_line (start -2.101 -1.601) (end 2.1 -1.601) (layer "F.SilkS") (width 0.15))
    (fp_line (start -2.101 1.58) (end -2.101 1.459) (layer "F.SilkS") (width 0.15))
    (fp_line (start -2.101 -1.601) (end -2.101 -1.48) (layer "F.SilkS") (width 0.15))
    (fp_line (start 2.1 -1.601) (end 2.1 -1.48) (layer "F.SilkS") (width 0.15))
    (fp_line (start 2.1 1.6) (end 2.1 1.499) (layer "F.SilkS") (width 0.15))
    (fp_line (start -2.101 1.6) (end 2.1 1.6) (layer "F.SilkS") (width 0.15))
    (fp_rect (start -2.751 -1.75) (end 2.748 1.749) (layer "F.CrtYd") (width 0.05) (fill none))
    (fp_line (start 2.1 -1.601) (end -2.101 -1.601) (layer "F.Fab") (width 0.15))
    (fp_line (start -2.101 -1.601) (end -2.101 1.6) (layer "F.Fab") (width 0.15))
    (fp_line (start -0.25 -0.802) (end 0.248 -0.802) (layer "F.Fab") (width 0.15))
    (fp_line (start -2.101 1.6) (end 2.1 1.6) (layer "F.Fab") (width 0.15))
    (fp_line (start 2.1 1.6) (end 2.1 -1.601) (layer "F.Fab") (width 0.15))
    (fp_line (start 0.248 0.8) (end -0.25 0.8) (layer "F.Fab") (width 0.15))
    (fp_arc (start -0.25 0.8) (mid -1.051001 -0.001) (end -0.25 -0.802) (layer "F.Fab") (width 0.15))
    (fp_arc (start 0.248 -0.802) (mid 1.050001 -0.001) (end 0.248 0.8) (layer "F.Fab") (width 0.15))
    (pad "1" smd rect (at 2.048 -0.802) (size 0.9 1) (layers "F.Cu" "F.Paste" "F.Mask")
      (net 1 "GND") (pintype "passive"))
    (pad "2" smd rect (at 2.048 0.8) (size 0.9 1) (layers "F.Cu" "F.Paste" "F.Mask")
      (net 345 "/SoM/VOL_UP_R") (pintype "passive"))
    (pad "3" smd rect (at -2.05 -0.802) (size 0.9 1) (layers "F.Cu" "F.Paste" "F.Mask")
      (net 1 "GND") (pintype "passive"))
    (pad "4" smd rect (at -2.05 0.8) (size 0.9 1) (layers "F.Cu" "F.Paste" "F.Mask")
      (net 345 "/SoM/VOL_UP_R") (pintype "passive"))
  )
)
